(kicad_pcb
	(version 20260206)
	(generator "pcbnew")
	(generator_version "10.0")
	(general
		(thickness 1.6)
		(legacy_teardrops no)
	)
	(paper "A4")
	(title_block
		(title "04192023_DAF0TMB3IC0_F0TG_MB_C_brd_V02_OCP.brd")
		(comment 1 "Grand Teton / footprints 8057-8063 of 8354")
	)
	(layers
		(0 "F.Cu" signal "TOP")
		(4 "In1.Cu" signal "GND")
		(6 "In2.Cu" signal "IN1")
		(8 "In3.Cu" signal "GND1")
		(10 "In4.Cu" signal "IN2")
		(12 "In5.Cu" signal "GND2")
		(14 "In6.Cu" signal "IN3")
		(16 "In7.Cu" signal "GND3")
		(18 "In8.Cu" signal "VCC")
		(20 "In9.Cu" signal "VCC1")
		(22 "In10.Cu" signal "GND4")
		(24 "In11.Cu" signal "IN4")
		(26 "In12.Cu" signal "GND5")
		(28 "In13.Cu" signal "IN5")
		(30 "In14.Cu" signal "GND6")
		(32 "In15.Cu" signal "IN6")
		(34 "In16.Cu" signal "GND7")
		(2 "B.Cu" signal "BOTTOM")
		(9 "F.Adhes" user "F.Adhesive")
		(11 "B.Adhes" user "B.Adhesive")
		(13 "F.Paste" user "Package Geometry/Pastemask Top")
		(15 "B.Paste" user "Package Geometry/Pastemask Bottom")
		(5 "F.SilkS" user "Ref Des/Silkscreen Top")
		(7 "B.SilkS" user "Ref Des/Silkscreen Bottom")
		(1 "F.Mask" user "Board Geometry/Soldermask Top")
		(3 "B.Mask" user "Board Geometry/Soldermask Bottom")
		(17 "Dwgs.User" user "User.Drawings")
		(19 "Cmts.User" user "User.Comments")
		(21 "Eco1.User" user "User.Eco1")
		(23 "Eco2.User" user "User.Eco2")
		(25 "Edge.Cuts" user "Board Geometry/Outline")
		(27 "Margin" user)
		(31 "F.CrtYd" user "Package Geometry/Place Bound Top")
		(29 "B.CrtYd" user "Package Geometry/Place Bound Bottom")
		(35 "F.Fab" user "Ref Des/Assembly Top")
		(33 "B.Fab" user "Ref Des/Assembly Bottom")
	)
	(footprint ""
		(layer "B.Cu")
		(at 257.232658 -327.684384 180)
		(property "Reference" "C1074"
			(at 0 0 0)
			(layer "B.SilkS")
			(hide yes)
			(effects
				(font
					(size 1.27 1.27)
				)
				(justify mirror)
			)
		)
		(property "Value" ""
			(at 0 0 0)
			(layer "B.Fab")
			(effects
				(font
					(size 1.27 1.27)
				)
				(justify mirror)
			)
		)
		(duplicate_pad_numbers_are_jumpers no)
		(fp_line
			(start 0.7874 0.4064)
			(end 0.7874 -0.4064)
			(stroke
				(width 0.1524)
				(type default)
			)
			(layer "B.SilkS")
		)
		(fp_line
			(start 0.7874 -0.4064)
			(end -0.7874 -0.4064)
			(stroke
				(width 0.1524)
				(type default)
			)
			(layer "B.SilkS")
		)
		(fp_line
			(start -0.7874 0.4064)
			(end 0.7874 0.4064)
			(stroke
				(width 0.1524)
				(type default)
			)
			(layer "B.SilkS")
		)
		(fp_line
			(start -0.7874 -0.4064)
			(end -0.7874 0.4064)
			(stroke
				(width 0.1524)
				(type default)
			)
			(layer "B.SilkS")
		)
		(fp_line
			(start 0.67945 0.3048)
			(end 0.67945 -0.305054)
			(stroke
				(width 0.1)
				(type default)
			)
			(layer "B.Fab")
		)
		(fp_line
			(start 0.67945 -0.305054)
			(end 0.12065 -0.305054)
			(stroke
				(width 0.1)
				(type default)
			)
			(layer "B.Fab")
		)
		(fp_line
			(start 0.12065 0.3048)
			(end 0.67945 0.3048)
			(stroke
				(width 0.1)
				(type default)
			)
			(layer "B.Fab")
		)
		(fp_line
			(start 0.12065 0.2794)
			(end 0.12065 0.3048)
			(stroke
				(width 0.1)
				(type default)
			)
			(layer "B.Fab")
		)
		(fp_line
			(start 0.12065 -0.2794)
			(end -0.12065 -0.2794)
			(stroke
				(width 0.1)
				(type default)
			)
			(layer "B.Fab")
		)
		(fp_line
			(start 0.12065 -0.305054)
			(end 0.12065 -0.2794)
			(stroke
				(width 0.1)
				(type default)
			)
			(layer "B.Fab")
		)
		(fp_line
			(start -0.120396 0.3048)
			(end -0.120396 0.2794)
			(stroke
				(width 0.1)
				(type default)
			)
			(layer "B.Fab")
		)
		(fp_line
			(start -0.120396 0.2794)
			(end 0.12065 0.2794)
			(stroke
				(width 0.1)
				(type default)
			)
			(layer "B.Fab")
		)
		(fp_line
			(start -0.12065 -0.2794)
			(end -0.12065 -0.3048)
			(stroke
				(width 0.1)
				(type default)
			)
			(layer "B.Fab")
		)
		(fp_line
			(start -0.12065 -0.3048)
			(end -0.67945 -0.3048)
			(stroke
				(width 0.1)
				(type default)
			)
			(layer "B.Fab")
		)
		(fp_line
			(start -0.67945 0.3048)
			(end -0.120396 0.3048)
			(stroke
				(width 0.1)
				(type default)
			)
			(layer "B.Fab")
		)
		(fp_line
			(start -0.67945 -0.3048)
			(end -0.67945 0.3048)
			(stroke
				(width 0.1)
				(type default)
			)
			(layer "B.Fab")
		)
		(pad "1" smd circle
			(at 0.40005 0)
			(size 0 0)
			(layers "B.Cu" "B.Mask" "B.Paste")
			(net "MAX11617_2_VREF")
		)
		(pad "2" smd circle
			(at -0.40005 0)
			(size 0 0)
			(layers "B.Cu" "B.Mask" "B.Paste")
			(net "GND")
		)
	)
	(footprint ""
		(layer "B.Cu")
		(at 189.879224 -145.585434)
		(property "Reference" "R8035"
			(at 0 0 0)
			(layer "B.SilkS")
			(hide yes)
			(effects
				(font
					(size 1.27 1.27)
				)
				(justify mirror)
			)
		)
		(property "Value" ""
			(at 0 0 0)
			(layer "B.Fab")
			(effects
				(font
					(size 1.27 1.27)
				)
				(justify mirror)
			)
		)
		(duplicate_pad_numbers_are_jumpers no)
		(fp_line
			(start -0.7874 -0.4064)
			(end -0.7874 0.4064)
			(stroke
				(width 0.1524)
				(type default)
			)
			(layer "B.SilkS")
		)
		(fp_line
			(start -0.7874 0.4064)
			(end 0.7874 0.4064)
			(stroke
				(width 0.1524)
				(type default)
			)
			(layer "B.SilkS")
		)
		(fp_line
			(start 0.7874 -0.4064)
			(end -0.7874 -0.4064)
			(stroke
				(width 0.1524)
				(type default)
			)
			(layer "B.SilkS")
		)
		(fp_line
			(start 0.7874 0.4064)
			(end 0.7874 -0.4064)
			(stroke
				(width 0.1524)
				(type default)
			)
			(layer "B.SilkS")
		)
		(fp_line
			(start -0.67945 -0.3048)
			(end -0.67945 0.3048)
			(stroke
				(width 0.1)
				(type default)
			)
			(layer "B.Fab")
		)
		(fp_line
			(start -0.67945 0.3048)
			(end -0.120396 0.3048)
			(stroke
				(width 0.1)
				(type default)
			)
			(layer "B.Fab")
		)
		(fp_line
			(start -0.12065 -0.3048)
			(end -0.67945 -0.3048)
			(stroke
				(width 0.1)
				(type default)
			)
			(layer "B.Fab")
		)
		(fp_line
			(start -0.12065 -0.2794)
			(end -0.12065 -0.3048)
			(stroke
				(width 0.1)
				(type default)
			)
			(layer "B.Fab")
		)
		(fp_line
			(start -0.120396 0.2794)
			(end 0.12065 0.2794)
			(stroke
				(width 0.1)
				(type default)
			)
			(layer "B.Fab")
		)
		(fp_line
			(start -0.120396 0.3048)
			(end -0.120396 0.2794)
			(stroke
				(width 0.1)
				(type default)
			)
			(layer "B.Fab")
		)
		(fp_line
			(start 0.12065 -0.305054)
			(end 0.12065 -0.2794)
			(stroke
				(width 0.1)
				(type default)
			)
			(layer "B.Fab")
		)
		(fp_line
			(start 0.12065 -0.2794)
			(end -0.12065 -0.2794)
			(stroke
				(width 0.1)
				(type default)
			)
			(layer "B.Fab")
		)
		(fp_line
			(start 0.12065 0.2794)
			(end 0.12065 0.3048)
			(stroke
				(width 0.1)
				(type default)
			)
			(layer "B.Fab")
		)
		(fp_line
			(start 0.12065 0.3048)
			(end 0.67945 0.3048)
			(stroke
				(width 0.1)
				(type default)
			)
			(layer "B.Fab")
		)
		(fp_line
			(start 0.67945 -0.305054)
			(end 0.12065 -0.305054)
			(stroke
				(width 0.1)
				(type default)
			)
			(layer "B.Fab")
		)
		(fp_line
			(start 0.67945 0.3048)
			(end 0.67945 -0.305054)
			(stroke
				(width 0.1)
				(type default)
			)
			(layer "B.Fab")
		)
		(pad "1" smd circle
			(at 0.40005 0 180)
			(size 0 0)
			(layers "B.Cu" "B.Mask" "B.Paste")
			(net "P1V8_AUX")
		)
		(pad "2" smd circle
			(at -0.40005 0 180)
			(size 0 0)
			(layers "B.Cu" "B.Mask" "B.Paste")
			(net "ESPI_CPU0_ALERT_N")
		)
	)
	(footprint ""
		(layer "B.Cu")
		(at 203.33208 -35.372548 180)
		(property "Reference" "R3579"
			(at 0 0 0)
			(layer "B.SilkS")
			(hide yes)
			(effects
				(font
					(size 1.27 1.27)
				)
				(justify mirror)
			)
		)
		(property "Value" ""
			(at 0 0 0)
			(layer "B.Fab")
			(effects
				(font
					(size 1.27 1.27)
				)
				(justify mirror)
			)
		)
		(duplicate_pad_numbers_are_jumpers no)
		(fp_line
			(start 0.7874 0.4064)
			(end 0.7874 -0.4064)
			(stroke
				(width 0.1524)
				(type default)
			)
			(layer "B.SilkS")
		)
		(fp_line
			(start 0.7874 -0.4064)
			(end -0.7874 -0.4064)
			(stroke
				(width 0.1524)
				(type default)
			)
			(layer "B.SilkS")
		)
		(fp_line
			(start -0.7874 0.4064)
			(end 0.7874 0.4064)
			(stroke
				(width 0.1524)
				(type default)
			)
			(layer "B.SilkS")
		)
		(fp_line
			(start -0.7874 -0.4064)
			(end -0.7874 0.4064)
			(stroke
				(width 0.1524)
				(type default)
			)
			(layer "B.SilkS")
		)
		(fp_line
			(start 0.67945 0.3048)
			(end 0.67945 -0.305054)
			(stroke
				(width 0.1)
				(type default)
			)
			(layer "B.Fab")
		)
		(fp_line
			(start 0.67945 -0.305054)
			(end 0.12065 -0.305054)
			(stroke
				(width 0.1)
				(type default)
			)
			(layer "B.Fab")
		)
		(fp_line
			(start 0.12065 0.3048)
			(end 0.67945 0.3048)
			(stroke
				(width 0.1)
				(type default)
			)
			(layer "B.Fab")
		)
		(fp_line
			(start 0.12065 0.2794)
			(end 0.12065 0.3048)
			(stroke
				(width 0.1)
				(type default)
			)
			(layer "B.Fab")
		)
		(fp_line
			(start 0.12065 -0.2794)
			(end -0.12065 -0.2794)
			(stroke
				(width 0.1)
				(type default)
			)
			(layer "B.Fab")
		)
		(fp_line
			(start 0.12065 -0.305054)
			(end 0.12065 -0.2794)
			(stroke
				(width 0.1)
				(type default)
			)
			(layer "B.Fab")
		)
		(fp_line
			(start -0.120396 0.3048)
			(end -0.120396 0.2794)
			(stroke
				(width 0.1)
				(type default)
			)
			(layer "B.Fab")
		)
		(fp_line
			(start -0.120396 0.2794)
			(end 0.12065 0.2794)
			(stroke
				(width 0.1)
				(type default)
			)
			(layer "B.Fab")
		)
		(fp_line
			(start -0.12065 -0.2794)
			(end -0.12065 -0.3048)
			(stroke
				(width 0.1)
				(type default)
			)
			(layer "B.Fab")
		)
		(fp_line
			(start -0.12065 -0.3048)
			(end -0.67945 -0.3048)
			(stroke
				(width 0.1)
				(type default)
			)
			(layer "B.Fab")
		)
		(fp_line
			(start -0.67945 0.3048)
			(end -0.120396 0.3048)
			(stroke
				(width 0.1)
				(type default)
			)
			(layer "B.Fab")
		)
		(fp_line
			(start -0.67945 -0.3048)
			(end -0.67945 0.3048)
			(stroke
				(width 0.1)
				(type default)
			)
			(layer "B.Fab")
		)
		(pad "1" smd circle
			(at 0.40005 0)
			(size 0 0)
			(layers "B.Cu" "B.Mask" "B.Paste")
			(net "P12V_SCM")
		)
		(pad "2" smd circle
			(at -0.40005 0)
			(size 0 0)
			(layers "B.Cu" "B.Mask" "B.Paste")
			(net "VSENSE_P12V_INA230_5_INN")
		)
	)
	(footprint ""
		(layer "B.Cu")
		(at 70.645528 -387.084062 -90)
		(property "Reference" "C113"
			(at 0 0 90)
			(layer "B.SilkS")
			(hide yes)
			(effects
				(font
					(size 1.27 1.27)
				)
				(justify mirror)
			)
		)
		(property "Value" ""
			(at 0 0 90)
			(layer "B.Fab")
			(effects
				(font
					(size 1.27 1.27)
				)
				(justify mirror)
			)
		)
		(duplicate_pad_numbers_are_jumpers no)
		(fp_line
			(start -1.524 0.762)
			(end 1.524 0.762)
			(stroke
				(width 0.1524)
				(type default)
			)
			(layer "B.SilkS")
		)
		(fp_line
			(start 1.524 0.762)
			(end 1.524 -0.762)
			(stroke
				(width 0.1524)
				(type default)
			)
			(layer "B.SilkS")
		)
		(fp_line
			(start -1.524 -0.762)
			(end -1.524 0.762)
			(stroke
				(width 0.1524)
				(type default)
			)
			(layer "B.SilkS")
		)
		(fp_line
			(start 1.524 -0.762)
			(end -1.524 -0.762)
			(stroke
				(width 0.1524)
				(type default)
			)
			(layer "B.SilkS")
		)
		(fp_line
			(start -1.1049 0.724916)
			(end -1.1049 -0.724916)
			(stroke
				(width 0.1)
				(type default)
			)
			(layer "B.Fab")
		)
		(fp_line
			(start 1.1049 0.724916)
			(end -1.1049 0.724916)
			(stroke
				(width 0.1)
				(type default)
			)
			(layer "B.Fab")
		)
		(fp_line
			(start -1.1049 -0.724916)
			(end 1.1049 -0.724916)
			(stroke
				(width 0.1)
				(type default)
			)
			(layer "B.Fab")
		)
		(fp_line
			(start 1.1049 -0.724916)
			(end 1.1049 0.724916)
			(stroke
				(width 0.1)
				(type default)
			)
			(layer "B.Fab")
		)
		(pad "1" smd rect
			(at 0.889 0 270)
			(size 1.016 1.27)
			(layers "B.Cu" "B.Mask" "B.Paste")
			(net "P1V8_CPU1_RT_1D")
		)
		(pad "2" smd rect
			(at -0.889 0 270)
			(size 1.016 1.27)
			(layers "B.Cu" "B.Mask" "B.Paste")
			(net "GND")
		)
	)
	(footprint ""
		(layer "B.Cu")
		(at 95.518986 -390.560052 90)
		(property "Reference" "C335"
			(at 0 0 90)
			(layer "B.SilkS")
			(hide yes)
			(effects
				(font
					(size 1.27 1.27)
				)
				(justify mirror)
			)
		)
		(property "Value" ""
			(at 0 0 90)
			(layer "B.Fab")
			(effects
				(font
					(size 1.27 1.27)
				)
				(justify mirror)
			)
		)
		(duplicate_pad_numbers_are_jumpers no)
		(fp_line
			(start 0.7874 -0.4064)
			(end -0.7874 -0.4064)
			(stroke
				(width 0.1524)
				(type default)
			)
			(layer "B.SilkS")
		)
		(fp_line
			(start -0.7874 -0.4064)
			(end -0.7874 0.4064)
			(stroke
				(width 0.1524)
				(type default)
			)
			(layer "B.SilkS")
		)
		(fp_line
			(start 0.7874 0.4064)
			(end 0.7874 -0.4064)
			(stroke
				(width 0.1524)
				(type default)
			)
			(layer "B.SilkS")
		)
		(fp_line
			(start -0.7874 0.4064)
			(end 0.7874 0.4064)
			(stroke
				(width 0.1524)
				(type default)
			)
			(layer "B.SilkS")
		)
		(fp_line
			(start 0.67945 -0.305054)
			(end 0.12065 -0.305054)
			(stroke
				(width 0.1)
				(type default)
			)
			(layer "B.Fab")
		)
		(fp_line
			(start 0.12065 -0.305054)
			(end 0.12065 -0.2794)
			(stroke
				(width 0.1)
				(type default)
			)
			(layer "B.Fab")
		)
		(fp_line
			(start -0.12065 -0.3048)
			(end -0.67945 -0.3048)
			(stroke
				(width 0.1)
				(type default)
			)
			(layer "B.Fab")
		)
		(fp_line
			(start -0.67945 -0.3048)
			(end -0.67945 0.3048)
			(stroke
				(width 0.1)
				(type default)
			)
			(layer "B.Fab")
		)
		(fp_line
			(start 0.12065 -0.2794)
			(end -0.12065 -0.2794)
			(stroke
				(width 0.1)
				(type default)
			)
			(layer "B.Fab")
		)
		(fp_line
			(start -0.12065 -0.2794)
			(end -0.12065 -0.3048)
			(stroke
				(width 0.1)
				(type default)
			)
			(layer "B.Fab")
		)
		(fp_line
			(start 0.12065 0.2794)
			(end 0.12065 0.3048)
			(stroke
				(width 0.1)
				(type default)
			)
			(layer "B.Fab")
		)
		(fp_line
			(start -0.120396 0.2794)
			(end 0.12065 0.2794)
			(stroke
				(width 0.1)
				(type default)
			)
			(layer "B.Fab")
		)
		(fp_line
			(start 0.67945 0.3048)
			(end 0.67945 -0.305054)
			(stroke
				(width 0.1)
				(type default)
			)
			(layer "B.Fab")
		)
		(fp_line
			(start 0.12065 0.3048)
			(end 0.67945 0.3048)
			(stroke
				(width 0.1)
				(type default)
			)
			(layer "B.Fab")
		)
		(fp_line
			(start -0.120396 0.3048)
			(end -0.120396 0.2794)
			(stroke
				(width 0.1)
				(type default)
			)
			(layer "B.Fab")
		)
		(fp_line
			(start -0.67945 0.3048)
			(end -0.120396 0.3048)
			(stroke
				(width 0.1)
				(type default)
			)
			(layer "B.Fab")
		)
		(pad "1" smd circle
			(at 0.40005 0 270)
			(size 0 0)
			(layers "B.Cu" "B.Mask" "B.Paste")
			(net "P0V9_CPU1_RT1_2A")
		)
		(pad "2" smd circle
			(at -0.40005 0 270)
			(size 0 0)
			(layers "B.Cu" "B.Mask" "B.Paste")
			(net "GND")
		)
	)
	(footprint ""
		(layer "B.Cu")
		(at 301.377604 -426.498512 180)
		(property "Reference" "R666"
			(at 0 0 0)
			(layer "B.SilkS")
			(hide yes)
			(effects
				(font
					(size 1.27 1.27)
				)
				(justify mirror)
			)
		)
		(property "Value" ""
			(at 0 0 0)
			(layer "B.Fab")
			(effects
				(font
					(size 1.27 1.27)
				)
				(justify mirror)
			)
		)
		(duplicate_pad_numbers_are_jumpers no)
		(fp_line
			(start 0.32512 0.175006)
			(end 0.32512 -0.175006)
			(stroke
				(width 0.1)
				(type default)
			)
			(layer "B.Fab")
		)
		(fp_line
			(start 0.32512 -0.175006)
			(end -0.32512 -0.175006)
			(stroke
				(width 0.1)
				(type default)
			)
			(layer "B.Fab")
		)
		(fp_line
			(start -0.32512 0.175006)
			(end 0.32512 0.175006)
			(stroke
				(width 0.1)
				(type default)
			)
			(layer "B.Fab")
		)
		(fp_line
			(start -0.32512 -0.175006)
			(end -0.32512 0.175006)
			(stroke
				(width 0.1)
				(type default)
			)
			(layer "B.Fab")
		)
		(pad "1" smd rect
			(at 0.2667 0)
			(size 0.3048 0.381)
			(layers "B.Cu" "B.Mask" "B.Paste")
			(net "SMB_RT_CPU0_P0_ROM_MUX_1D_SCL")
		)
		(pad "2" smd rect
			(at -0.2667 0 180)
			(size 0.3048 0.381)
			(layers "B.Cu" "B.Mask" "B.Paste")
			(net "SMB_RT_CPU0_P0_ROM_MUX_1D_R_SCL")
		)
	)
	(footprint ""
		(layer "B.Cu")
		(at 94.460314 -307.730652 180)
		(property "Reference" "R491"
			(at 0 0 0)
			(layer "B.SilkS")
			(hide yes)
			(effects
				(font
					(size 1.27 1.27)
				)
				(justify mirror)
			)
		)
		(property "Value" ""
			(at 0 0 0)
			(layer "B.Fab")
			(effects
				(font
					(size 1.27 1.27)
				)
				(justify mirror)
			)
		)
		(duplicate_pad_numbers_are_jumpers no)
		(fp_line
			(start 0.7874 0.4064)
			(end 0.7874 -0.4064)
			(stroke
				(width 0.1524)
				(type default)
			)
			(layer "B.SilkS")
		)
		(fp_line
			(start 0.7874 -0.4064)
			(end -0.7874 -0.4064)
			(stroke
				(width 0.1524)
				(type default)
			)
			(layer "B.SilkS")
		)
		(fp_line
			(start -0.7874 0.4064)
			(end 0.7874 0.4064)
			(stroke
				(width 0.1524)
				(type default)
			)
			(layer "B.SilkS")
		)
		(fp_line
			(start -0.7874 -0.4064)
			(end -0.7874 0.4064)
			(stroke
				(width 0.1524)
				(type default)
			)
			(layer "B.SilkS")
		)
		(fp_line
			(start 0.67945 0.3048)
			(end 0.67945 -0.305054)
			(stroke
				(width 0.1)
				(type default)
			)
			(layer "B.Fab")
		)
		(fp_line
			(start 0.67945 -0.305054)
			(end 0.12065 -0.305054)
			(stroke
				(width 0.1)
				(type default)
			)
			(layer "B.Fab")
		)
		(fp_line
			(start 0.12065 0.3048)
			(end 0.67945 0.3048)
			(stroke
				(width 0.1)
				(type default)
			)
			(layer "B.Fab")
		)
		(fp_line
			(start 0.12065 0.2794)
			(end 0.12065 0.3048)
			(stroke
				(width 0.1)
				(type default)
			)
			(layer "B.Fab")
		)
		(fp_line
			(start 0.12065 -0.2794)
			(end -0.12065 -0.2794)
			(stroke
				(width 0.1)
				(type default)
			)
			(layer "B.Fab")
		)
		(fp_line
			(start 0.12065 -0.305054)
			(end 0.12065 -0.2794)
			(stroke
				(width 0.1)
				(type default)
			)
			(layer "B.Fab")
		)
		(fp_line
			(start -0.120396 0.3048)
			(end -0.120396 0.2794)
			(stroke
				(width 0.1)
				(type default)
			)
			(layer "B.Fab")
		)
		(fp_line
			(start -0.120396 0.2794)
			(end 0.12065 0.2794)
			(stroke
				(width 0.1)
				(type default)
			)
			(layer "B.Fab")
		)
		(fp_line
			(start -0.12065 -0.2794)
			(end -0.12065 -0.3048)
			(stroke
				(width 0.1)
				(type default)
			)
			(layer "B.Fab")
		)
		(fp_line
			(start -0.12065 -0.3048)
			(end -0.67945 -0.3048)
			(stroke
				(width 0.1)
				(type default)
			)
			(layer "B.Fab")
		)
		(fp_line
			(start -0.67945 0.3048)
			(end -0.120396 0.3048)
			(stroke
				(width 0.1)
				(type default)
			)
			(layer "B.Fab")
		)
		(fp_line
			(start -0.67945 -0.3048)
			(end -0.67945 0.3048)
			(stroke
				(width 0.1)
				(type default)
			)
			(layer "B.Fab")
		)
		(pad "1" smd circle
			(at 0.40005 0)
			(size 0 0)
			(layers "B.Cu" "B.Mask" "B.Paste")
			(net "GND")
		)
		(pad "2" smd circle
			(at -0.40005 0)
			(size 0 0)
			(layers "B.Cu" "B.Mask" "B.Paste")
			(net "CPU1_PWRGD_OUT")
		)
	)
)
